# T6G (Grand Teton) — schematic netlist excerpt (pin names and nets, part order shuffled) for the footprints in the layout excerpt that follows; sources: Cadence DE-HDL packaged netlist, KiCad conversion of 04192023_DAF0TMB3IC0_F0TG_MB_C_brd_V02_OCP.brd

J105  CONN112_10137002101LF  CONN112_10137002-101LF IO  pkg HSD_F112D8_P2W1-2_RDH  page 115
  A1  = GPU_3V3IO_RSVD4
  A2  = GND
  A3  = GPU_WP_HW_CTRL_ISO_N
  A4  = GND
  A5  = GPU_3V3IO_RSVD3
  A6  = GND
  A7  = GPU_3V3IO_RSVD1
  A8  = GND
  B1  = GND
  B2  = P5E_CPU0_P2_RX_BUF_DN<9>
  B3  = GND
  B4  = P5E_CPU0_P2_RX_BUF_DN<11>
  B5  = GND
  B6  = P5E_CPU0_P2_RX_BUF_DN<13>
  B7  = GND
  B8  = P5E_CPU0_P2_RX_BUF_DN<15>
  C1  = P5E_CPU0_P2_RX_BUF_DN<8>
  C2  = P5E_CPU0_P2_RX_BUF_DP<9>
  C3  = P5E_CPU0_P2_RX_BUF_DN<10>
  C4  = P5E_CPU0_P2_RX_BUF_DP<11>
  C5  = P5E_CPU0_P2_RX_BUF_DN<12>
  C6  = P5E_CPU0_P2_RX_BUF_DP<13>
  C7  = P5E_CPU0_P2_RX_BUF_DN<14>
  C8  = P5E_CPU0_P2_RX_BUF_DP<15>
  D1  = P5E_CPU0_P2_RX_BUF_DP<8>
  D2  = GND
  D3  = P5E_CPU0_P2_RX_BUF_DP<10>
  D4  = GND
  D5  = P5E_CPU0_P2_RX_BUF_DP<12>
  D6  = GND
  D7  = P5E_CPU0_P2_RX_BUF_DP<14>
  D8  = GND
  E1  = GND
  E2  = P5E_CPU0_P3_RX_BUF_DN<9>
  E3  = GND
  E4  = P5E_CPU0_P3_RX_BUF_DN<11>
  E5  = GND
  E6  = P5E_CPU0_P3_RX_BUF_DN<13>
  E7  = GND
  E8  = P5E_CPU0_P3_RX_BUF_DN<15>
  F1  = P5E_CPU0_P3_RX_BUF_DN<8>
  F2  = P5E_CPU0_P3_RX_BUF_DP<9>
  F3  = P5E_CPU0_P3_RX_BUF_DN<10>
  F4  = P5E_CPU0_P3_RX_BUF_DP<11>
  F5  = P5E_CPU0_P3_RX_BUF_DN<12>
  F6  = P5E_CPU0_P3_RX_BUF_DP<13>
  F7  = P5E_CPU0_P3_RX_BUF_DN<14>
  F8  = P5E_CPU0_P3_RX_BUF_DP<15>
  G1  = P5E_CPU0_P3_RX_BUF_DP<8>
  G2  = GND
  G3  = P5E_CPU0_P3_RX_BUF_DP<10>
  G4  = GND
  G5  = P5E_CPU0_P3_RX_BUF_DP<12>
  G6  = GND
  G7  = P5E_CPU0_P3_RX_BUF_DP<14>
  G8  = GND
  H1  = GND
  H2  = P5E_CPU0_P2_TX_BUF_C_DN<9>
  H3  = GND
  H4  = P5E_CPU0_P2_TX_BUF_C_DN<11>
  H5  = GND
  H6  = P5E_CPU0_P2_TX_BUF_C_DN<13>
  H7  = GND
  H8  = P5E_CPU0_P2_TX_BUF_C_DN<15>
  I1  = P5E_CPU0_P2_TX_BUF_C_DN<8>
  I2  = P5E_CPU0_P2_TX_BUF_C_DP<9>
  I3  = P5E_CPU0_P2_TX_BUF_C_DN<10>
  I4  = P5E_CPU0_P2_TX_BUF_C_DP<11>
  I5  = P5E_CPU0_P2_TX_BUF_C_DN<12>
  I6  = P5E_CPU0_P2_TX_BUF_C_DP<13>
  I7  = P5E_CPU0_P2_TX_BUF_C_DN<14>
  I8  = P5E_CPU0_P2_TX_BUF_C_DP<15>
  J1  = P5E_CPU0_P2_TX_BUF_C_DP<8>
  J2  = GND
  J3  = P5E_CPU0_P2_TX_BUF_C_DP<10>
  J4  = GND
  J5  = P5E_CPU0_P2_TX_BUF_C_DP<12>
  J6  = GND
  J7  = P5E_CPU0_P2_TX_BUF_C_DP<14>
  J8  = GND
  K1  = GND
  K2  = P5E_CPU0_P3_TX_BUF_C_DN<9>
  K3  = GND
  K4  = P5E_CPU0_P3_TX_BUF_C_DN<11>
  K5  = GND
  K6  = P5E_CPU0_P3_TX_BUF_C_DN<13>
  K7  = GND
  K8  = P5E_CPU0_P3_TX_BUF_C_DN<15>
  L1  = P5E_CPU0_P3_TX_BUF_C_DN<8>
  L2  = P5E_CPU0_P3_TX_BUF_C_DP<9>
  L3  = P5E_CPU0_P3_TX_BUF_C_DN<10>
  L4  = P5E_CPU0_P3_TX_BUF_C_DP<11>
  L5  = P5E_CPU0_P3_TX_BUF_C_DN<12>
  L6  = P5E_CPU0_P3_TX_BUF_C_DP<13>
  L7  = P5E_CPU0_P3_TX_BUF_C_DN<14>
  L8  = P5E_CPU0_P3_TX_BUF_C_DP<15>
  M1  = P5E_CPU0_P3_TX_BUF_C_DP<8>
  M2  = GND
  M3  = P5E_CPU0_P3_TX_BUF_C_DP<10>
  M4  = GND
  M5  = P5E_CPU0_P3_TX_BUF_C_DP<12>
  M6  = GND
  M7  = P5E_CPU0_P3_TX_BUF_C_DP<14>
  M8  = GND
  N1  = GND
  N2  = FM_SWB_PWR_EN_R_BUF
  N3  = GND
  N4  = FM_SWB_BIC_READY_N
  N5  = GND
  N6  = RST_SWB_BIC_BUF_N
  N7  = GND
  N8  = RST_BMC_FROM_SWB_N

(kicad_pcb
	(version 20260206)
	(generator "pcbnew")
	(generator_version "10.0")
	(general
		(thickness 1.6)
		(legacy_teardrops no)
	)
	(paper "A4")
	(title_block
		(title "04192023_DAF0TMB3IC0_F0TG_MB_C_brd_V02_OCP.brd")
		(comment 1 "Grand Teton / footprint 3508 of 8354 (J105), pads 32-48 of 48")
	)
	(layers
		(0 "F.Cu" signal "TOP")
		(4 "In1.Cu" signal "GND")
		(6 "In2.Cu" signal "IN1")
		(8 "In3.Cu" signal "GND1")
		(10 "In4.Cu" signal "IN2")
		(12 "In5.Cu" signal "GND2")
		(14 "In6.Cu" signal "IN3")
		(16 "In7.Cu" signal "GND3")
		(18 "In8.Cu" signal "VCC")
		(20 "In9.Cu" signal "VCC1")
		(22 "In10.Cu" signal "GND4")
		(24 "In11.Cu" signal "IN4")
		(26 "In12.Cu" signal "GND5")
		(28 "In13.Cu" signal "IN5")
		(30 "In14.Cu" signal "GND6")
		(32 "In15.Cu" signal "IN6")
		(34 "In16.Cu" signal "GND7")
		(2 "B.Cu" signal "BOTTOM")
		(9 "F.Adhes" user "F.Adhesive")
		(11 "B.Adhes" user "B.Adhesive")
		(13 "F.Paste" user "Package Geometry/Pastemask Top")
		(15 "B.Paste" user "Package Geometry/Pastemask Bottom")
		(5 "F.SilkS" user "Ref Des/Silkscreen Top")
		(7 "B.SilkS" user "Ref Des/Silkscreen Bottom")
		(1 "F.Mask" user "Board Geometry/Soldermask Top")
		(3 "B.Mask" user "Board Geometry/Soldermask Bottom")
		(17 "Dwgs.User" user "User.Drawings")
		(19 "Cmts.User" user "User.Comments")
		(21 "Eco1.User" user "User.Eco1")
		(23 "Eco2.User" user "User.Eco2")
		(25 "Edge.Cuts" user "Board Geometry/Outline")
		(27 "Margin" user)
		(31 "F.CrtYd" user "Package Geometry/Place Bound Top")
		(29 "B.CrtYd" user "Package Geometry/Place Bound Bottom")
		(35 "F.Fab" user "Ref Des/Assembly Top")
		(33 "B.Fab" user "Ref Des/Assembly Bottom")
	)
	(footprint ""
		(layer "F.Cu")
		(at 398.750028 -440.489848)
		(property "Reference" "J105"
			(at 19.875754 19.509486 0)
			(unlocked yes)
			(layer "F.SilkS")
			(effects
				(font
					(size 0.7874 0.5842)
					(thickness 0.1524)
				)
				(justify left)
			)
		)
		(property "Value" ""
			(at 0 0 0)
			(layer "F.Fab")
			(effects
				(font
					(size 1.27 1.27)
				)
			)
		)
		(duplicate_pad_numbers_are_jumpers no)
		(pad "J8" thru_hole circle
			(at 13.999972 10.999978 180)
			(size 0.906272 0.906272)
			(drill 0.499872)
			(layers "*.Cu" "*.Mask")
			(remove_unused_layers no)
			(net "GND")
			(clearance 0.0508)
			(thermal_gap 0.0508)
		)
		(pad "K1" thru_hole circle
			(at 0 11.999976 180)
			(size 0.906272 0.906272)
			(drill 0.499872)
			(layers "*.Cu" "*.Mask")
			(remove_unused_layers no)
			(net "GND")
			(clearance 0.0508)
			(thermal_gap 0.0508)
		)
		(pad "K3" thru_hole circle
			(at 3.999992 11.999976 180)
			(size 0.906272 0.906272)
			(drill 0.499872)
			(layers "*.Cu" "*.Mask")
			(remove_unused_layers no)
			(net "GND")
			(clearance 0.0508)
			(thermal_gap 0.0508)
		)
		(pad "K5" thru_hole circle
			(at 7.999984 11.999976 180)
			(size 0.906272 0.906272)
			(drill 0.499872)
			(layers "*.Cu" "*.Mask")
			(remove_unused_layers no)
			(net "GND")
			(clearance 0.0508)
			(thermal_gap 0.0508)
		)
		(pad "K7" thru_hole circle
			(at 11.999976 11.999976 180)
			(size 0.906272 0.906272)
			(drill 0.499872)
			(layers "*.Cu" "*.Mask")
			(remove_unused_layers no)
			(net "GND")
			(clearance 0.0508)
			(thermal_gap 0.0508)
		)
		(pad "M2" thru_hole circle
			(at 1.999996 14.59992 180)
			(size 0.906272 0.906272)
			(drill 0.499872)
			(layers "*.Cu" "*.Mask")
			(remove_unused_layers no)
			(net "GND")
			(clearance 0.0508)
			(thermal_gap 0.0508)
		)
		(pad "M4" thru_hole circle
			(at 5.999988 14.59992 180)
			(size 0.906272 0.906272)
			(drill 0.499872)
			(layers "*.Cu" "*.Mask")
			(remove_unused_layers no)
			(net "GND")
			(clearance 0.0508)
			(thermal_gap 0.0508)
		)
		(pad "M6" thru_hole circle
			(at 9.99998 14.59992 180)
			(size 0.906272 0.906272)
			(drill 0.499872)
			(layers "*.Cu" "*.Mask")
			(remove_unused_layers no)
			(net "GND")
			(clearance 0.0508)
			(thermal_gap 0.0508)
		)
		(pad "M8" thru_hole circle
			(at 13.999972 14.59992 180)
			(size 0.906272 0.906272)
			(drill 0.499872)
			(layers "*.Cu" "*.Mask")
			(remove_unused_layers no)
			(net "GND")
			(clearance 0.0508)
			(thermal_gap 0.0508)
		)
		(pad "N1" thru_hole circle
			(at 0 15.599918 180)
			(size 0.906272 0.906272)
			(drill 0.499872)
			(layers "*.Cu" "*.Mask")
			(remove_unused_layers no)
			(net "GND")
			(clearance 0.0508)
			(thermal_gap 0.0508)
		)
		(pad "N2" thru_hole circle
			(at 1.999996 15.80007 180)
			(size 0.766318 0.766318)
			(drill 0.359918)
			(layers "*.Cu" "*.Mask")
			(remove_unused_layers no)
			(net "FM_SWB_PWR_EN_R_BUF")
			(clearance 0.0508)
			(thermal_gap 0.0508)
		)
		(pad "N3" thru_hole circle
			(at 3.999992 15.599918 180)
			(size 0.906272 0.906272)
			(drill 0.499872)
			(layers "*.Cu" "*.Mask")
			(remove_unused_layers no)
			(net "GND")
			(clearance 0.0508)
			(thermal_gap 0.0508)
		)
		(pad "N4" thru_hole circle
			(at 5.999988 15.80007 180)
			(size 0.766318 0.766318)
			(drill 0.359918)
			(layers "*.Cu" "*.Mask")
			(remove_unused_layers no)
			(net "FM_SWB_BIC_READY_N")
			(clearance 0.0508)
			(thermal_gap 0.0508)
		)
		(pad "N5" thru_hole circle
			(at 7.999984 15.599918 180)
			(size 0.906272 0.906272)
			(drill 0.499872)
			(layers "*.Cu" "*.Mask")
			(remove_unused_layers no)
			(net "GND")
			(clearance 0.0508)
			(thermal_gap 0.0508)
		)
		(pad "N6" thru_hole circle
			(at 9.99998 15.80007 180)
			(size 0.766318 0.766318)
			(drill 0.359918)
			(layers "*.Cu" "*.Mask")
			(remove_unused_layers no)
			(net "RST_SWB_BIC_BUF_N")
			(clearance 0.0508)
			(thermal_gap 0.0508)
		)
		(pad "N7" thru_hole circle
			(at 11.999976 15.599918 180)
			(size 0.906272 0.906272)
			(drill 0.499872)
			(layers "*.Cu" "*.Mask")
			(remove_unused_layers no)
			(net "GND")
			(clearance 0.0508)
			(thermal_gap 0.0508)
		)
		(pad "N8" thru_hole circle
			(at 13.999972 15.80007 180)
			(size 0.766318 0.766318)
			(drill 0.359918)
			(layers "*.Cu" "*.Mask")
			(remove_unused_layers no)
			(net "RST_BMC_FROM_SWB_N")
			(clearance 0.0508)
			(thermal_gap 0.0508)
		)
	)
)
